# S9S_MB_2U (Grand Teton) — schematic netlist excerpt (pin names and nets, part order shuffled) for the footprints in the layout excerpt that follows; sources: Cadence DE-HDL packaged netlist, KiCad conversion of 03242023_DA0F0TMBIJ0_F0T_Motherboard_J_brd_V01_OCP.brd

R4609  Q_RES  33.2 1% CHIP  pkg 0402LF  page 214 : A = FM_JTAG_TCK_MUX_SEL_R ; B = FM_JTAG_TCK_MUX_SEL
R1308  Q_RES  10K 1% EMPTY  pkg 0402LF  page 220 : A = FM_RST_PERST_BIT1 ; B = GND

(kicad_pcb
	(version 20260206)
	(generator "pcbnew")
	(generator_version "10.0")
	(general
		(thickness 1.6)
		(legacy_teardrops no)
	)
	(paper "A4")
	(title_block
		(title "03242023_DA0F0TMBIJ0_F0T_Motherboard_J_brd_V01_OCP.brd")
		(comment 1 "Grand Teton / footprints 1829-1830 of 6105")
	)
	(layers
		(0 "F.Cu" signal "TOP")
		(4 "In1.Cu" signal "GND")
		(6 "In2.Cu" signal "IN1")
		(8 "In3.Cu" signal "GND1")
		(10 "In4.Cu" signal "IN2")
		(12 "In5.Cu" signal "GND2")
		(14 "In6.Cu" signal "IN3")
		(16 "In7.Cu" signal "GND3")
		(18 "In8.Cu" signal "VCC")
		(20 "In9.Cu" signal "VCC1")
		(22 "In10.Cu" signal "GND4")
		(24 "In11.Cu" signal "IN4")
		(26 "In12.Cu" signal "GND5")
		(28 "In13.Cu" signal "IN5")
		(30 "In14.Cu" signal "GND6")
		(32 "In15.Cu" signal "IN6")
		(34 "In16.Cu" signal "GND7")
		(2 "B.Cu" signal "BOTTOM")
		(9 "F.Adhes" user "F.Adhesive")
		(11 "B.Adhes" user "B.Adhesive")
		(13 "F.Paste" user "Package Geometry/Pastemask Top")
		(15 "B.Paste" user "Package Geometry/Pastemask Bottom")
		(5 "F.SilkS" user "Ref Des/Silkscreen Top")
		(7 "B.SilkS" user "Ref Des/Silkscreen Bottom")
		(1 "F.Mask" user "Board Geometry/Soldermask Top")
		(3 "B.Mask" user "Board Geometry/Soldermask Bottom")
		(17 "Dwgs.User" user "User.Drawings")
		(19 "Cmts.User" user "User.Comments")
		(21 "Eco1.User" user "User.Eco1")
		(23 "Eco2.User" user "User.Eco2")
		(25 "Edge.Cuts" user "Board Geometry/Outline")
		(27 "Margin" user)
		(31 "F.CrtYd" user "Package Geometry/Place Bound Top")
		(29 "B.CrtYd" user "Package Geometry/Place Bound Bottom")
		(35 "F.Fab" user "Ref Des/Assembly Top")
		(33 "B.Fab" user "Ref Des/Assembly Bottom")
	)
	(footprint ""
		(layer "F.Cu")
		(at 195.06184 -92.832428 90)
		(property "Reference" "R4609"
			(at 0 0 90)
			(layer "F.SilkS")
			(hide yes)
			(effects
				(font
					(size 1.27 1.27)
				)
			)
		)
		(property "Value" ""
			(at 0 0 90)
			(layer "F.Fab")
			(effects
				(font
					(size 1.27 1.27)
				)
			)
		)
		(duplicate_pad_numbers_are_jumpers no)
		(fp_line
			(start 0.7874 -0.4064)
			(end 0.7874 0.4064)
			(stroke
				(width 0.1524)
				(type default)
			)
			(layer "F.SilkS")
		)
		(fp_line
			(start -0.7874 -0.4064)
			(end 0.7874 -0.4064)
			(stroke
				(width 0.1524)
				(type default)
			)
			(layer "F.SilkS")
		)
		(fp_line
			(start 0.7874 0.4064)
			(end -0.7874 0.4064)
			(stroke
				(width 0.1524)
				(type default)
			)
			(layer "F.SilkS")
		)
		(fp_line
			(start -0.7874 0.4064)
			(end -0.7874 -0.4064)
			(stroke
				(width 0.1524)
				(type default)
			)
			(layer "F.SilkS")
		)
		(fp_line
			(start -0.12065 -0.305054)
			(end -0.12065 -0.2794)
			(stroke
				(width 0.1)
				(type default)
			)
			(layer "F.Fab")
		)
		(fp_line
			(start -0.67945 -0.305054)
			(end -0.12065 -0.305054)
			(stroke
				(width 0.1)
				(type default)
			)
			(layer "F.Fab")
		)
		(fp_line
			(start 0.67945 -0.3048)
			(end 0.67945 0.3048)
			(stroke
				(width 0.1)
				(type default)
			)
			(layer "F.Fab")
		)
		(fp_line
			(start 0.12065 -0.3048)
			(end 0.67945 -0.3048)
			(stroke
				(width 0.1)
				(type default)
			)
			(layer "F.Fab")
		)
		(fp_line
			(start 0.12065 -0.2794)
			(end 0.12065 -0.3048)
			(stroke
				(width 0.1)
				(type default)
			)
			(layer "F.Fab")
		)
		(fp_line
			(start -0.12065 -0.2794)
			(end 0.12065 -0.2794)
			(stroke
				(width 0.1)
				(type default)
			)
			(layer "F.Fab")
		)
		(fp_line
			(start 0.120396 0.2794)
			(end -0.12065 0.2794)
			(stroke
				(width 0.1)
				(type default)
			)
			(layer "F.Fab")
		)
		(fp_line
			(start -0.12065 0.2794)
			(end -0.12065 0.3048)
			(stroke
				(width 0.1)
				(type default)
			)
			(layer "F.Fab")
		)
		(fp_line
			(start 0.67945 0.3048)
			(end 0.120396 0.3048)
			(stroke
				(width 0.1)
				(type default)
			)
			(layer "F.Fab")
		)
		(fp_line
			(start 0.120396 0.3048)
			(end 0.120396 0.2794)
			(stroke
				(width 0.1)
				(type default)
			)
			(layer "F.Fab")
		)
		(fp_line
			(start -0.12065 0.3048)
			(end -0.67945 0.3048)
			(stroke
				(width 0.1)
				(type default)
			)
			(layer "F.Fab")
		)
		(fp_line
			(start -0.67945 0.3048)
			(end -0.67945 -0.305054)
			(stroke
				(width 0.1)
				(type default)
			)
			(layer "F.Fab")
		)
		(pad "1" smd circle
			(at -0.40005 0 90)
			(size 0 0)
			(layers "F.Cu" "F.Mask" "F.Paste")
			(net "FM_JTAG_TCK_MUX_SEL_R")
		)
		(pad "2" smd circle
			(at 0.40005 0 90)
			(size 0 0)
			(layers "F.Cu" "F.Mask" "F.Paste")
			(net "FM_JTAG_TCK_MUX_SEL")
		)
	)
	(footprint ""
		(layer "F.Cu")
		(at 190.80988 -133.695948 90)
		(property "Reference" "R1308"
			(at 0 0 90)
			(layer "F.SilkS")
			(hide yes)
			(effects
				(font
					(size 1.27 1.27)
				)
			)
		)
		(property "Value" ""
			(at 0 0 90)
			(layer "F.Fab")
			(effects
				(font
					(size 1.27 1.27)
				)
			)
		)
		(duplicate_pad_numbers_are_jumpers no)
		(fp_line
			(start 0.7874 -0.4064)
			(end 0.7874 0.4064)
			(stroke
				(width 0.1524)
				(type default)
			)
			(layer "F.SilkS")
		)
		(fp_line
			(start -0.7874 -0.4064)
			(end 0.7874 -0.4064)
			(stroke
				(width 0.1524)
				(type default)
			)
			(layer "F.SilkS")
		)
		(fp_line
			(start 0.7874 0.4064)
			(end -0.7874 0.4064)
			(stroke
				(width 0.1524)
				(type default)
			)
			(layer "F.SilkS")
		)
		(fp_line
			(start -0.7874 0.4064)
			(end -0.7874 -0.4064)
			(stroke
				(width 0.1524)
				(type default)
			)
			(layer "F.SilkS")
		)
		(fp_line
			(start -0.12065 -0.305054)
			(end -0.12065 -0.2794)
			(stroke
				(width 0.1)
				(type default)
			)
			(layer "F.Fab")
		)
		(fp_line
			(start -0.67945 -0.305054)
			(end -0.12065 -0.305054)
			(stroke
				(width 0.1)
				(type default)
			)
			(layer "F.Fab")
		)
		(fp_line
			(start 0.67945 -0.3048)
			(end 0.67945 0.3048)
			(stroke
				(width 0.1)
				(type default)
			)
			(layer "F.Fab")
		)
		(fp_line
			(start 0.12065 -0.3048)
			(end 0.67945 -0.3048)
			(stroke
				(width 0.1)
				(type default)
			)
			(layer "F.Fab")
		)
		(fp_line
			(start 0.12065 -0.2794)
			(end 0.12065 -0.3048)
			(stroke
				(width 0.1)
				(type default)
			)
			(layer "F.Fab")
		)
		(fp_line
			(start -0.12065 -0.2794)
			(end 0.12065 -0.2794)
			(stroke
				(width 0.1)
				(type default)
			)
			(layer "F.Fab")
		)
		(fp_line
			(start 0.120396 0.2794)
			(end -0.12065 0.2794)
			(stroke
				(width 0.1)
				(type default)
			)
			(layer "F.Fab")
		)
		(fp_line
			(start -0.12065 0.2794)
			(end -0.12065 0.3048)
			(stroke
				(width 0.1)
				(type default)
			)
			(layer "F.Fab")
		)
		(fp_line
			(start 0.67945 0.3048)
			(end 0.120396 0.3048)
			(stroke
				(width 0.1)
				(type default)
			)
			(layer "F.Fab")
		)
		(fp_line
			(start 0.120396 0.3048)
			(end 0.120396 0.2794)
			(stroke
				(width 0.1)
				(type default)
			)
			(layer "F.Fab")
		)
		(fp_line
			(start -0.12065 0.3048)
			(end -0.67945 0.3048)
			(stroke
				(width 0.1)
				(type default)
			)
			(layer "F.Fab")
		)
		(fp_line
			(start -0.67945 0.3048)
			(end -0.67945 -0.305054)
			(stroke
				(width 0.1)
				(type default)
			)
			(layer "F.Fab")
		)
		(pad "1" smd circle
			(at -0.40005 0 90)
			(size 0 0)
			(layers "F.Cu" "F.Mask" "F.Paste")
			(net "FM_RST_PERST_BIT1")
		)
		(pad "2" smd circle
			(at 0.40005 0 90)
			(size 0 0)
			(layers "F.Cu" "F.Mask" "F.Paste")
			(net "GND")
		)
	)
)
